(kicad_pcb
	(version 20260206)
	(generator "pcbnew")
	(generator_version "10.0")
	(general
		(thickness 1.6)
		(legacy_teardrops no)
	)
	(paper "A4")
	(title_block
		(title "04192023_DAF0TMB3IC0_F0TG_MB_C_brd_V02_OCP.brd")
		(comment 1 "Grand Teton / footprints 2208-2212 of 8354")
	)
	(layers
		(0 "F.Cu" signal "TOP")
		(4 "In1.Cu" signal "GND")
		(6 "In2.Cu" signal "IN1")
		(8 "In3.Cu" signal "GND1")
		(10 "In4.Cu" signal "IN2")
		(12 "In5.Cu" signal "GND2")
		(14 "In6.Cu" signal "IN3")
		(16 "In7.Cu" signal "GND3")
		(18 "In8.Cu" signal "VCC")
		(20 "In9.Cu" signal "VCC1")
		(22 "In10.Cu" signal "GND4")
		(24 "In11.Cu" signal "IN4")
		(26 "In12.Cu" signal "GND5")
		(28 "In13.Cu" signal "IN5")
		(30 "In14.Cu" signal "GND6")
		(32 "In15.Cu" signal "IN6")
		(34 "In16.Cu" signal "GND7")
		(2 "B.Cu" signal "BOTTOM")
		(9 "F.Adhes" user "F.Adhesive")
		(11 "B.Adhes" user "B.Adhesive")
		(13 "F.Paste" user "Package Geometry/Pastemask Top")
		(15 "B.Paste" user "Package Geometry/Pastemask Bottom")
		(5 "F.SilkS" user "Ref Des/Silkscreen Top")
		(7 "B.SilkS" user "Ref Des/Silkscreen Bottom")
		(1 "F.Mask" user "Board Geometry/Soldermask Top")
		(3 "B.Mask" user "Board Geometry/Soldermask Bottom")
		(17 "Dwgs.User" user "User.Drawings")
		(19 "Cmts.User" user "User.Comments")
		(21 "Eco1.User" user "User.Eco1")
		(23 "Eco2.User" user "User.Eco2")
		(25 "Edge.Cuts" user "Board Geometry/Outline")
		(27 "Margin" user)
		(31 "F.CrtYd" user "Package Geometry/Place Bound Top")
		(29 "B.CrtYd" user "Package Geometry/Place Bound Bottom")
		(35 "F.Fab" user "Ref Des/Assembly Top")
		(33 "B.Fab" user "Ref Des/Assembly Bottom")
	)
	(footprint ""
		(layer "F.Cu")
		(at 50.20183 -33.575498 90)
		(property "Reference" "R3205"
			(at 0 0 90)
			(layer "F.SilkS")
			(hide yes)
			(effects
				(font
					(size 1.27 1.27)
				)
			)
		)
		(property "Value" ""
			(at 0 0 90)
			(layer "F.Fab")
			(effects
				(font
					(size 1.27 1.27)
				)
			)
		)
		(duplicate_pad_numbers_are_jumpers no)
		(fp_line
			(start 0.7874 -0.4064)
			(end 0.7874 0.4064)
			(stroke
				(width 0.1524)
				(type default)
			)
			(layer "F.SilkS")
		)
		(fp_line
			(start -0.7874 -0.4064)
			(end 0.7874 -0.4064)
			(stroke
				(width 0.1524)
				(type default)
			)
			(layer "F.SilkS")
		)
		(fp_line
			(start 0.7874 0.4064)
			(end -0.7874 0.4064)
			(stroke
				(width 0.1524)
				(type default)
			)
			(layer "F.SilkS")
		)
		(fp_line
			(start -0.7874 0.4064)
			(end -0.7874 -0.4064)
			(stroke
				(width 0.1524)
				(type default)
			)
			(layer "F.SilkS")
		)
		(fp_line
			(start -0.12065 -0.305054)
			(end -0.12065 -0.2794)
			(stroke
				(width 0.1)
				(type default)
			)
			(layer "F.Fab")
		)
		(fp_line
			(start -0.67945 -0.305054)
			(end -0.12065 -0.305054)
			(stroke
				(width 0.1)
				(type default)
			)
			(layer "F.Fab")
		)
		(fp_line
			(start 0.67945 -0.3048)
			(end 0.67945 0.3048)
			(stroke
				(width 0.1)
				(type default)
			)
			(layer "F.Fab")
		)
		(fp_line
			(start 0.12065 -0.3048)
			(end 0.67945 -0.3048)
			(stroke
				(width 0.1)
				(type default)
			)
			(layer "F.Fab")
		)
		(fp_line
			(start 0.12065 -0.2794)
			(end 0.12065 -0.3048)
			(stroke
				(width 0.1)
				(type default)
			)
			(layer "F.Fab")
		)
		(fp_line
			(start -0.12065 -0.2794)
			(end 0.12065 -0.2794)
			(stroke
				(width 0.1)
				(type default)
			)
			(layer "F.Fab")
		)
		(fp_line
			(start 0.120396 0.2794)
			(end -0.12065 0.2794)
			(stroke
				(width 0.1)
				(type default)
			)
			(layer "F.Fab")
		)
		(fp_line
			(start -0.12065 0.2794)
			(end -0.12065 0.3048)
			(stroke
				(width 0.1)
				(type default)
			)
			(layer "F.Fab")
		)
		(fp_line
			(start 0.67945 0.3048)
			(end 0.120396 0.3048)
			(stroke
				(width 0.1)
				(type default)
			)
			(layer "F.Fab")
		)
		(fp_line
			(start 0.120396 0.3048)
			(end 0.120396 0.2794)
			(stroke
				(width 0.1)
				(type default)
			)
			(layer "F.Fab")
		)
		(fp_line
			(start -0.12065 0.3048)
			(end -0.67945 0.3048)
			(stroke
				(width 0.1)
				(type default)
			)
			(layer "F.Fab")
		)
		(fp_line
			(start -0.67945 0.3048)
			(end -0.67945 -0.305054)
			(stroke
				(width 0.1)
				(type default)
			)
			(layer "F.Fab")
		)
		(pad "1" smd circle
			(at -0.40005 0 90)
			(size 0 0)
			(layers "F.Cu" "F.Mask" "F.Paste")
			(net "FB_BMC_ISOLATE_R2")
		)
		(pad "2" smd circle
			(at 0.40005 0 90)
			(size 0 0)
			(layers "F.Cu" "F.Mask" "F.Paste")
			(net "FB_BMC_ISOLATE1")
		)
	)
	(footprint ""
		(layer "F.Cu")
		(at 187.569348 -349.58655 90)
		(property "Reference" "PR519"
			(at 0 0 90)
			(layer "F.SilkS")
			(hide yes)
			(effects
				(font
					(size 1.27 1.27)
				)
			)
		)
		(property "Value" ""
			(at 0 0 90)
			(layer "F.Fab")
			(effects
				(font
					(size 1.27 1.27)
				)
			)
		)
		(duplicate_pad_numbers_are_jumpers no)
		(fp_line
			(start 0.7874 -0.4064)
			(end 0.7874 0.4064)
			(stroke
				(width 0.1524)
				(type default)
			)
			(layer "F.SilkS")
		)
		(fp_line
			(start -0.7874 -0.4064)
			(end 0.7874 -0.4064)
			(stroke
				(width 0.1524)
				(type default)
			)
			(layer "F.SilkS")
		)
		(fp_line
			(start 0.7874 0.4064)
			(end -0.7874 0.4064)
			(stroke
				(width 0.1524)
				(type default)
			)
			(layer "F.SilkS")
		)
		(fp_line
			(start -0.7874 0.4064)
			(end -0.7874 -0.4064)
			(stroke
				(width 0.1524)
				(type default)
			)
			(layer "F.SilkS")
		)
		(fp_line
			(start -0.12065 -0.305054)
			(end -0.12065 -0.2794)
			(stroke
				(width 0.1)
				(type default)
			)
			(layer "F.Fab")
		)
		(fp_line
			(start -0.67945 -0.305054)
			(end -0.12065 -0.305054)
			(stroke
				(width 0.1)
				(type default)
			)
			(layer "F.Fab")
		)
		(fp_line
			(start 0.67945 -0.3048)
			(end 0.67945 0.3048)
			(stroke
				(width 0.1)
				(type default)
			)
			(layer "F.Fab")
		)
		(fp_line
			(start 0.12065 -0.3048)
			(end 0.67945 -0.3048)
			(stroke
				(width 0.1)
				(type default)
			)
			(layer "F.Fab")
		)
		(fp_line
			(start 0.12065 -0.2794)
			(end 0.12065 -0.3048)
			(stroke
				(width 0.1)
				(type default)
			)
			(layer "F.Fab")
		)
		(fp_line
			(start -0.12065 -0.2794)
			(end 0.12065 -0.2794)
			(stroke
				(width 0.1)
				(type default)
			)
			(layer "F.Fab")
		)
		(fp_line
			(start 0.120396 0.2794)
			(end -0.12065 0.2794)
			(stroke
				(width 0.1)
				(type default)
			)
			(layer "F.Fab")
		)
		(fp_line
			(start -0.12065 0.2794)
			(end -0.12065 0.3048)
			(stroke
				(width 0.1)
				(type default)
			)
			(layer "F.Fab")
		)
		(fp_line
			(start 0.67945 0.3048)
			(end 0.120396 0.3048)
			(stroke
				(width 0.1)
				(type default)
			)
			(layer "F.Fab")
		)
		(fp_line
			(start 0.120396 0.3048)
			(end 0.120396 0.2794)
			(stroke
				(width 0.1)
				(type default)
			)
			(layer "F.Fab")
		)
		(fp_line
			(start -0.12065 0.3048)
			(end -0.67945 0.3048)
			(stroke
				(width 0.1)
				(type default)
			)
			(layer "F.Fab")
		)
		(fp_line
			(start -0.67945 0.3048)
			(end -0.67945 -0.305054)
			(stroke
				(width 0.1)
				(type default)
			)
			(layer "F.Fab")
		)
		(pad "1" smd circle
			(at -0.40005 0 90)
			(size 0 0)
			(layers "F.Cu" "F.Mask" "F.Paste")
			(net "SW_PVDD11_S3_P1_SW2_RC")
		)
		(pad "2" smd circle
			(at 0.40005 0 90)
			(size 0 0)
			(layers "F.Cu" "F.Mask" "F.Paste")
			(net "GND")
		)
	)
	(footprint ""
		(layer "F.Cu")
		(at 201.676 -92.964)
		(property "Reference" "D8006"
			(at 4.037076 -0.588518 0)
			(unlocked yes)
			(layer "F.SilkS")
			(effects
				(font
					(size 0.7874 0.5842)
					(thickness 0.1524)
				)
				(justify left)
			)
		)
		(property "Value" ""
			(at 0 0 0)
			(layer "F.Fab")
			(effects
				(font
					(size 1.27 1.27)
				)
			)
		)
		(duplicate_pad_numbers_are_jumpers no)
		(fp_line
			(start -2.050796 -0.700024)
			(end 2.050796 -0.700024)
			(stroke
				(width 0.1524)
				(type default)
			)
			(layer "F.SilkS")
		)
		(fp_line
			(start -2.050796 0.700024)
			(end -2.050796 -0.700024)
			(stroke
				(width 0.1524)
				(type default)
			)
			(layer "F.SilkS")
		)
		(fp_line
			(start -0.30607 -0.500126)
			(end -0.30607 0.500126)
			(stroke
				(width 0.1524)
				(type default)
			)
			(layer "F.SilkS")
		)
		(fp_line
			(start -0.30607 0.500126)
			(end 0.193802 0)
			(stroke
				(width 0.1524)
				(type default)
			)
			(layer "F.SilkS")
		)
		(fp_line
			(start 0.193802 0)
			(end -0.30607 -0.500126)
			(stroke
				(width 0.1524)
				(type default)
			)
			(layer "F.SilkS")
		)
		(fp_line
			(start 0.293878 -0.500126)
			(end 0.293878 0.500126)
			(stroke
				(width 0.1524)
				(type default)
			)
			(layer "F.SilkS")
		)
		(fp_line
			(start 2.050796 -0.700024)
			(end 2.050796 0.700024)
			(stroke
				(width 0.1524)
				(type default)
			)
			(layer "F.SilkS")
		)
		(fp_line
			(start 2.050796 0.700024)
			(end -2.050796 0.700024)
			(stroke
				(width 0.1524)
				(type default)
			)
			(layer "F.SilkS")
		)
		(fp_line
			(start 2.051304 0.635)
			(end 2.152904 0.635)
			(stroke
				(width 0.1524)
				(type default)
			)
			(layer "F.SilkS")
		)
		(fp_line
			(start 2.051304 0.6985)
			(end 2.051304 0.635)
			(stroke
				(width 0.1524)
				(type default)
			)
			(layer "F.SilkS")
		)
		(fp_line
			(start 2.064004 -0.6985)
			(end 2.229104 -0.6985)
			(stroke
				(width 0.1524)
				(type default)
			)
			(layer "F.SilkS")
		)
		(fp_line
			(start 2.064004 -0.6731)
			(end 2.064004 -0.6985)
			(stroke
				(width 0.1524)
				(type default)
			)
			(layer "F.SilkS")
		)
		(fp_line
			(start 2.152904 -0.6985)
			(end 2.343404 -0.6985)
			(stroke
				(width 0.1524)
				(type default)
			)
			(layer "F.SilkS")
		)
		(fp_line
			(start 2.152904 0.635)
			(end 2.152904 -0.6985)
			(stroke
				(width 0.1524)
				(type default)
			)
			(layer "F.SilkS")
		)
		(fp_line
			(start 2.229104 -0.6985)
			(end 2.229104 0.6985)
			(stroke
				(width 0.1524)
				(type default)
			)
			(layer "F.SilkS")
		)
		(fp_line
			(start 2.229104 0.6985)
			(end 2.051304 0.6985)
			(stroke
				(width 0.1524)
				(type default)
			)
			(layer "F.SilkS")
		)
		(fp_line
			(start 2.343404 -0.6985)
			(end 2.343404 0.6985)
			(stroke
				(width 0.1524)
				(type default)
			)
			(layer "F.SilkS")
		)
		(fp_line
			(start 2.343404 0.6985)
			(end 2.216404 0.6985)
			(stroke
				(width 0.1524)
				(type default)
			)
			(layer "F.SilkS")
		)
		(fp_line
			(start -0.899922 -0.700024)
			(end 0.899922 -0.700024)
			(stroke
				(width 0.1)
				(type default)
			)
			(layer "F.Fab")
		)
		(fp_line
			(start -0.899922 0.700024)
			(end -0.899922 -0.700024)
			(stroke
				(width 0.1)
				(type default)
			)
			(layer "F.Fab")
		)
		(fp_line
			(start 0.899922 -0.700024)
			(end 0.899922 0.700024)
			(stroke
				(width 0.1)
				(type default)
			)
			(layer "F.Fab")
		)
		(fp_line
			(start 0.899922 0.700024)
			(end -0.899922 0.700024)
			(stroke
				(width 0.1)
				(type default)
			)
			(layer "F.Fab")
		)
		(fp_text user "+"
			(at -2.066544 -0.757682 90)
			(unlocked yes)
			(layer "F.SilkS")
			(effects
				(font
					(size 1.905 1.4224)
					(thickness 0.1524)
				)
				(justify left)
			)
		)
		(fp_text user "-"
			(at 3.880104 0.23495 180)
			(unlocked yes)
			(layer "F.SilkS")
			(effects
				(font
					(size 1.905 1.4224)
					(thickness 0.1524)
				)
				(justify left)
			)
		)
		(fp_text user "+"
			(at -3.123946 0.762 90)
			(unlocked yes)
			(layer "F.Fab")
			(effects
				(font
					(size 1.905 1.4224)
					(thickness 0.1524)
				)
				(justify left)
			)
		)
		(fp_text user "-"
			(at 3.880104 0.23495 180)
			(unlocked yes)
			(layer "F.Fab")
			(effects
				(font
					(size 1.905 1.4224)
					(thickness 0.1524)
				)
				(justify left)
			)
		)
		(pad "1" smd rect
			(at -1.199896 0 270)
			(size 0.6604 1.3716)
			(layers "F.Cu" "F.Mask" "F.Paste")
			(net "PWRGD_CHGL_CPU1_R1")
		)
		(pad "2" smd rect
			(at 1.199896 0 90)
			(size 0.6604 1.3716)
			(layers "F.Cu" "F.Mask" "F.Paste")
			(net "P3V3_AUX")
		)
	)
	(footprint ""
		(layer "F.Cu")
		(at 215.904064 -23.304754 -90)
		(property "Reference" "R1139"
			(at 0 0 270)
			(layer "F.SilkS")
			(hide yes)
			(effects
				(font
					(size 1.27 1.27)
				)
			)
		)
		(property "Value" ""
			(at 0 0 270)
			(layer "F.Fab")
			(effects
				(font
					(size 1.27 1.27)
				)
			)
		)
		(duplicate_pad_numbers_are_jumpers no)
		(fp_line
			(start -0.7874 0.4064)
			(end -0.7874 -0.4064)
			(stroke
				(width 0.1524)
				(type default)
			)
			(layer "F.SilkS")
		)
		(fp_line
			(start 0.7874 0.4064)
			(end -0.7874 0.4064)
			(stroke
				(width 0.1524)
				(type default)
			)
			(layer "F.SilkS")
		)
		(fp_line
			(start -0.7874 -0.4064)
			(end 0.7874 -0.4064)
			(stroke
				(width 0.1524)
				(type default)
			)
			(layer "F.SilkS")
		)
		(fp_line
			(start 0.7874 -0.4064)
			(end 0.7874 0.4064)
			(stroke
				(width 0.1524)
				(type default)
			)
			(layer "F.SilkS")
		)
		(fp_line
			(start -0.67945 0.3048)
			(end -0.67945 -0.305054)
			(stroke
				(width 0.1)
				(type default)
			)
			(layer "F.Fab")
		)
		(fp_line
			(start -0.12065 0.3048)
			(end -0.67945 0.3048)
			(stroke
				(width 0.1)
				(type default)
			)
			(layer "F.Fab")
		)
		(fp_line
			(start 0.120396 0.3048)
			(end 0.120396 0.2794)
			(stroke
				(width 0.1)
				(type default)
			)
			(layer "F.Fab")
		)
		(fp_line
			(start 0.67945 0.3048)
			(end 0.120396 0.3048)
			(stroke
				(width 0.1)
				(type default)
			)
			(layer "F.Fab")
		)
		(fp_line
			(start -0.12065 0.2794)
			(end -0.12065 0.3048)
			(stroke
				(width 0.1)
				(type default)
			)
			(layer "F.Fab")
		)
		(fp_line
			(start 0.120396 0.2794)
			(end -0.12065 0.2794)
			(stroke
				(width 0.1)
				(type default)
			)
			(layer "F.Fab")
		)
		(fp_line
			(start -0.12065 -0.2794)
			(end 0.12065 -0.2794)
			(stroke
				(width 0.1)
				(type default)
			)
			(layer "F.Fab")
		)
		(fp_line
			(start 0.12065 -0.2794)
			(end 0.12065 -0.3048)
			(stroke
				(width 0.1)
				(type default)
			)
			(layer "F.Fab")
		)
		(fp_line
			(start 0.12065 -0.3048)
			(end 0.67945 -0.3048)
			(stroke
				(width 0.1)
				(type default)
			)
			(layer "F.Fab")
		)
		(fp_line
			(start 0.67945 -0.3048)
			(end 0.67945 0.3048)
			(stroke
				(width 0.1)
				(type default)
			)
			(layer "F.Fab")
		)
		(fp_line
			(start -0.67945 -0.305054)
			(end -0.12065 -0.305054)
			(stroke
				(width 0.1)
				(type default)
			)
			(layer "F.Fab")
		)
		(fp_line
			(start -0.12065 -0.305054)
			(end -0.12065 -0.2794)
			(stroke
				(width 0.1)
				(type default)
			)
			(layer "F.Fab")
		)
		(pad "1" smd circle
			(at -0.40005 0 270)
			(size 0 0)
			(layers "F.Cu" "F.Mask" "F.Paste")
			(net "CLK_50M_RMII")
		)
		(pad "2" smd circle
			(at 0.40005 0 270)
			(size 0 0)
			(layers "F.Cu" "F.Mask" "F.Paste")
			(net "CLK_50M_RMII_R")
		)
	)
	(footprint ""
		(layer "F.Cu")
		(at 19.666458 -418.690298 90)
		(property "Reference" "R6175"
			(at 0 0 90)
			(layer "F.SilkS")
			(hide yes)
			(effects
				(font
					(size 1.27 1.27)
				)
			)
		)
		(property "Value" ""
			(at 0 0 90)
			(layer "F.Fab")
			(effects
				(font
					(size 1.27 1.27)
				)
			)
		)
		(duplicate_pad_numbers_are_jumpers no)
		(fp_line
			(start 0.7874 -0.4064)
			(end 0.7874 0.4064)
			(stroke
				(width 0.1524)
				(type default)
			)
			(layer "F.SilkS")
		)
		(fp_line
			(start -0.7874 -0.4064)
			(end 0.7874 -0.4064)
			(stroke
				(width 0.1524)
				(type default)
			)
			(layer "F.SilkS")
		)
		(fp_line
			(start 0.7874 0.4064)
			(end -0.7874 0.4064)
			(stroke
				(width 0.1524)
				(type default)
			)
			(layer "F.SilkS")
		)
		(fp_line
			(start -0.7874 0.4064)
			(end -0.7874 -0.4064)
			(stroke
				(width 0.1524)
				(type default)
			)
			(layer "F.SilkS")
		)
		(fp_line
			(start -0.12065 -0.305054)
			(end -0.12065 -0.2794)
			(stroke
				(width 0.1)
				(type default)
			)
			(layer "F.Fab")
		)
		(fp_line
			(start -0.67945 -0.305054)
			(end -0.12065 -0.305054)
			(stroke
				(width 0.1)
				(type default)
			)
			(layer "F.Fab")
		)
		(fp_line
			(start 0.67945 -0.3048)
			(end 0.67945 0.3048)
			(stroke
				(width 0.1)
				(type default)
			)
			(layer "F.Fab")
		)
		(fp_line
			(start 0.12065 -0.3048)
			(end 0.67945 -0.3048)
			(stroke
				(width 0.1)
				(type default)
			)
			(layer "F.Fab")
		)
		(fp_line
			(start 0.12065 -0.2794)
			(end 0.12065 -0.3048)
			(stroke
				(width 0.1)
				(type default)
			)
			(layer "F.Fab")
		)
		(fp_line
			(start -0.12065 -0.2794)
			(end 0.12065 -0.2794)
			(stroke
				(width 0.1)
				(type default)
			)
			(layer "F.Fab")
		)
		(fp_line
			(start 0.120396 0.2794)
			(end -0.12065 0.2794)
			(stroke
				(width 0.1)
				(type default)
			)
			(layer "F.Fab")
		)
		(fp_line
			(start -0.12065 0.2794)
			(end -0.12065 0.3048)
			(stroke
				(width 0.1)
				(type default)
			)
			(layer "F.Fab")
		)
		(fp_line
			(start 0.67945 0.3048)
			(end 0.120396 0.3048)
			(stroke
				(width 0.1)
				(type default)
			)
			(layer "F.Fab")
		)
		(fp_line
			(start 0.120396 0.3048)
			(end 0.120396 0.2794)
			(stroke
				(width 0.1)
				(type default)
			)
			(layer "F.Fab")
		)
		(fp_line
			(start -0.12065 0.3048)
			(end -0.67945 0.3048)
			(stroke
				(width 0.1)
				(type default)
			)
			(layer "F.Fab")
		)
		(fp_line
			(start -0.67945 0.3048)
			(end -0.67945 -0.305054)
			(stroke
				(width 0.1)
				(type default)
			)
			(layer "F.Fab")
		)
		(pad "1" smd circle
			(at -0.40005 0 90)
			(size 0 0)
			(layers "F.Cu" "F.Mask" "F.Paste")
			(net "P3V3_AUX")
		)
		(pad "2" smd circle
			(at 0.40005 0 90)
			(size 0 0)
			(layers "F.Cu" "F.Mask" "F.Paste")
			(net "FM_P2E_BUF2_RXDET")
		)
	)
)
